(kicad_pcb
	(version 20241229)
	(generator "pcbnew")
	(generator_version "9.0")
	(general
		(thickness 1.6296)
		(legacy_teardrops no)
	)
	(paper "A3")
	(title_block
		(title "Thunderbolt to 10GbE adapter")
		(date "2026-04-21")
		(rev "1.1.0")
		(company "Antmicro Ltd")
		(comment 1 "www.antmicro.com")
		(comment 9 "footprint 288 of 703 (U14), pads 401-479 of 503")
	)
	(layers
		(0 "F.Cu" signal)
		(4 "In1.Cu" signal)
		(6 "In2.Cu" signal)
		(8 "In3.Cu" signal)
		(10 "In4.Cu" signal)
		(12 "In5.Cu" signal)
		(14 "In6.Cu" signal)
		(2 "B.Cu" signal)
		(9 "F.Adhes" user "F.Adhesive")
		(11 "B.Adhes" user "B.Adhesive")
		(13 "F.Paste" user)
		(15 "B.Paste" user)
		(5 "F.SilkS" user "F.Silkscreen")
		(7 "B.SilkS" user "B.Silkscreen")
		(1 "F.Mask" user)
		(3 "B.Mask" user)
		(17 "Dwgs.User" user "User.Drawings")
		(19 "Cmts.User" user "User.Comments")
		(21 "Eco1.User" user "User.Eco1")
		(23 "Eco2.User" user "User.Eco2")
		(25 "Edge.Cuts" user)
		(27 "Margin" user)
		(31 "F.CrtYd" user "F.Courtyard")
		(29 "B.CrtYd" user "B.Courtyard")
		(35 "F.Fab" user)
		(33 "B.Fab" user)
	)
	(footprint "antmicro-footprints:FCBGA-503_22x22mm_Layout21x24_P1mm"
		(layer "F.Cu")
		(at 151.005 81.499999 -90)
		(property "Reference" "U14"
			(at -11.499999 11.005 0)
			(layer "F.SilkS")
			(effects
				(font
					(size 0.7 0.7)
					(thickness 0.15)
				)
				(justify left bottom)
			)
		)
		(property "Value" "EZX710AT2_S_LMR5"
			(at -11.4 12.5 270)
			(layer "F.Fab")
			(effects
				(font
					(size 0.7 0.7)
					(thickness 0.15)
				)
				(justify left bottom)
			)
		)
		(property "Datasheet" "https://www.google.com/url?sa=t&source=web&rct=j&opi=89978449&url=https://cdrdv2-public.intel.com/596333/596333_X710-TM4_Datasheet_v_2_4.pdf&ved=2ahUKEwiSuv20_sCOAxXVCRAIHdxGO_UQFnoECBEQAQ&usg=AOvVaw1CjGyrGWE8ZvOdw4VBsY6U"
			(at 0 0 270)
			(layer "F.Fab")
			(effects
				(font
					(size 0.7 0.7)
					(thickness 0.15)
				)
				(justify left bottom)
			)
		)
		(property "Description" "Ethernet ICs Intel Ethernet Controller 10 Gigabit X7"
			(at 0 0 270)
			(layer "F.Fab")
			(effects
				(font
					(size 0.7 0.7)
					(thickness 0.15)
				)
				(justify left bottom)
			)
		)
		(property "MPN" "EZX710AT2 S LMR5"
			(at 0 0 270)
			(unlocked yes)
			(layer "F.Fab")
			(hide yes)
			(effects
				(font
					(size 1 1)
					(thickness 0.15)
				)
			)
		)
		(property "Manufacturer" "Intel"
			(at 0 0 270)
			(unlocked yes)
			(layer "F.Fab")
			(hide yes)
			(effects
				(font
					(size 1 1)
					(thickness 0.15)
				)
			)
		)
		(property "Author" "Antmicro"
			(at 0 0 270)
			(unlocked yes)
			(layer "F.Fab")
			(hide yes)
			(effects
				(font
					(size 1 1)
					(thickness 0.15)
				)
			)
		)
		(property "License" "Apache-2.0"
			(at 0 0 270)
			(unlocked yes)
			(layer "F.Fab")
			(hide yes)
			(effects
				(font
					(size 1 1)
					(thickness 0.15)
				)
			)
		)
		(sheetname "/X710-AT2 power/")
		(sheetfile "x710-at2-power.kicad_sch")
		(attr smd)
		(pad "T6" smd circle
			(at -7.75 3.025 270)
			(size 0.5 0.5)
			(layers "F.Cu" "F.Mask" "F.Paste")
			(net 66 "/2xRJ45/~{P1_LED_LINK_10G}")
			(pinfunction "LED2_1")
			(pintype "output")
		)
		(pad "T8" smd circle
			(at -6.75 3.025 270)
			(size 0.5 0.5)
			(layers "F.Cu" "F.Mask" "F.Paste")
			(net 9 "VCCD")
			(pinfunction "RSVDT8_VCCD")
			(pintype "passive")
		)
		(pad "T10" smd circle
			(at -5.75 3.025 270)
			(size 0.5 0.5)
			(layers "F.Cu" "F.Mask" "F.Paste")
			(net 23 "GND")
			(pinfunction "VSS")
			(pintype "passive")
		)
		(pad "T12" smd circle
			(at -4.75 3.025 270)
			(size 0.5 0.5)
			(layers "F.Cu" "F.Mask" "F.Paste")
			(net 23 "GND")
			(pinfunction "VSS")
			(pintype "passive")
		)
		(pad "T14" smd circle
			(at -3.75 3.025 270)
			(size 0.5 0.5)
			(layers "F.Cu" "F.Mask" "F.Paste")
			(net 23 "GND")
			(pinfunction "VSS")
			(pintype "passive")
		)
		(pad "T16" smd circle
			(at -2.75 3.025 270)
			(size 0.5 0.5)
			(layers "F.Cu" "F.Mask" "F.Paste")
			(net 23 "GND")
			(pinfunction "VSS")
			(pintype "passive")
		)
		(pad "T18" smd circle
			(at -1.75 3.025 270)
			(size 0.5 0.5)
			(layers "F.Cu" "F.Mask" "F.Paste")
			(net 23 "GND")
			(pinfunction "VSS")
			(pintype "passive")
		)
		(pad "T20" smd circle
			(at -0.75 3.025 270)
			(size 0.5 0.5)
			(layers "F.Cu" "F.Mask" "F.Paste")
			(net 23 "GND")
			(pinfunction "VSS")
			(pintype "passive")
		)
		(pad "T22" smd circle
			(at 0.25 3.025 270)
			(size 0.5 0.5)
			(layers "F.Cu" "F.Mask" "F.Paste")
			(net 573 "unconnected-(U14E-RSVDT22_NC-PadT22)")
			(pinfunction "RSVDT22_NC")
			(pintype "passive+no_connect")
		)
		(pad "T24" smd circle
			(at 1.25 3.025 270)
			(size 0.5 0.5)
			(layers "F.Cu" "F.Mask" "F.Paste")
			(net 462 "unconnected-(U14E-RSVDT24_NC-PadT24)")
			(pinfunction "RSVDT24_NC")
			(pintype "passive+no_connect")
		)
		(pad "T26" smd circle
			(at 2.25 3.025 270)
			(size 0.5 0.5)
			(layers "F.Cu" "F.Mask" "F.Paste")
			(net 493 "unconnected-(U14E-RSVDT26_NC-PadT26)")
			(pinfunction "RSVDT26_NC")
			(pintype "passive+no_connect")
		)
		(pad "T28" smd circle
			(at 3.25 3.025 270)
			(size 0.5 0.5)
			(layers "F.Cu" "F.Mask" "F.Paste")
			(net 530 "unconnected-(U14E-RSVDT28_NC-PadT28)")
			(pinfunction "RSVDT28_NC")
			(pintype "passive+no_connect")
		)
		(pad "T30" smd circle
			(at 4.25 3.025 270)
			(size 0.5 0.5)
			(layers "F.Cu" "F.Mask" "F.Paste")
			(net 519 "unconnected-(U14G-RSVDT30_NC-PadT30)")
			(pinfunction "RSVDT30_NC")
			(pintype "passive+no_connect")
		)
		(pad "T32" smd circle
			(at 5.25 3.025 270)
			(size 0.5 0.5)
			(layers "F.Cu" "F.Mask" "F.Paste")
			(net 485 "unconnected-(U14G-RSVDT32_NC-PadT32)")
			(pinfunction "RSVDT32_NC")
			(pintype "passive+no_connect")
		)
		(pad "T34" smd circle
			(at 6.25 3.025 270)
			(size 0.5 0.5)
			(layers "F.Cu" "F.Mask" "F.Paste")
			(net 7 "+3V3")
			(pinfunction "VCC3P3")
			(pintype "passive")
		)
		(pad "T36" smd circle
			(at 7.25 3.025 270)
			(size 0.5 0.5)
			(layers "F.Cu" "F.Mask" "F.Paste")
			(net 11 "/X710-AT2 PCIe/PCIe_JTAG.JTDI")
			(pinfunction "JTDI")
			(pintype "input")
		)
		(pad "T38" smd circle
			(at 8.25 3.025 270)
			(size 0.5 0.5)
			(layers "F.Cu" "F.Mask" "F.Paste")
			(net 8 "/X710-AT2 PCIe/PCIe_JTAG.JTDO")
			(pinfunction "JTDO")
			(pintype "open_collector")
		)
		(pad "T40" smd circle
			(at 9.25 3.025 270)
			(size 0.5 0.5)
			(layers "F.Cu" "F.Mask" "F.Paste")
			(net 445 "Net-(U14D-SMBD)")
			(pinfunction "SMBD")
			(pintype "open_collector")
		)
		(pad "T42" smd circle
			(at 10.25 3.025 270)
			(size 0.5 0.5)
			(layers "F.Cu" "F.Mask" "F.Paste")
			(net 351 "/X710 flash memory/FLASH.MISO")
			(pinfunction "FLSH_SO")
			(pintype "input")
		)
		(pad "U1" smd circle
			(at -10.25 3.89 270)
			(size 0.5 0.5)
			(layers "F.Cu" "F.Mask" "F.Paste")
			(net 23 "GND")
			(pinfunction "VSS_SVR")
			(pintype "power_in")
		)
		(pad "U3" smd circle
			(at -9.25 3.89 270)
			(size 0.5 0.5)
			(layers "F.Cu" "F.Mask" "F.Paste")
			(net 126 "/X710-AT2 Misc/~{PCI_DIS}")
			(pinfunction "~{PCI_DIS}")
			(pintype "tri_state")
		)
		(pad "U5" smd circle
			(at -8.25 3.89 270)
			(size 0.5 0.5)
			(layers "F.Cu" "F.Mask" "F.Paste")
			(net 469 "unconnected-(U14C-LED1_0-PadU5)")
			(pinfunction "LED1_0")
			(pintype "passive+no_connect")
		)
		(pad "U7" smd circle
			(at -7.25 3.89 270)
			(size 0.5 0.5)
			(layers "F.Cu" "F.Mask" "F.Paste")
			(net 457 "unconnected-(U14C-LED1_1-PadU7)")
			(pinfunction "LED1_1")
			(pintype "passive+no_connect")
		)
		(pad "U9" smd circle
			(at -6.25 3.89 270)
			(size 0.5 0.5)
			(layers "F.Cu" "F.Mask" "F.Paste")
			(net 557 "unconnected-(U14E-RSVDU9_NC-PadU9)")
			(pinfunction "RSVDU9_NC")
			(pintype "passive+no_connect")
		)
		(pad "U11" smd circle
			(at -5.25 3.89 270)
			(size 0.5 0.5)
			(layers "F.Cu" "F.Mask" "F.Paste")
			(net 9 "VCCD")
			(pinfunction "VCCD")
			(pintype "passive")
		)
		(pad "U13" smd circle
			(at -4.25 3.89 270)
			(size 0.5 0.5)
			(layers "F.Cu" "F.Mask" "F.Paste")
			(net 9 "VCCD")
			(pinfunction "VCCD")
			(pintype "passive")
		)
		(pad "U15" smd circle
			(at -3.25 3.89 270)
			(size 0.5 0.5)
			(layers "F.Cu" "F.Mask" "F.Paste")
			(net 9 "VCCD")
			(pinfunction "VCCD")
			(pintype "passive")
		)
		(pad "U17" smd circle
			(at -2.25 3.89 270)
			(size 0.5 0.5)
			(layers "F.Cu" "F.Mask" "F.Paste")
			(net 9 "VCCD")
			(pinfunction "VCCD")
			(pintype "passive")
		)
		(pad "U19" smd circle
			(at -1.25 3.89 270)
			(size 0.5 0.5)
			(layers "F.Cu" "F.Mask" "F.Paste")
			(net 9 "VCCD")
			(pinfunction "VCCD")
			(pintype "passive")
		)
		(pad "U21" smd circle
			(at -0.25 3.89 270)
			(size 0.5 0.5)
			(layers "F.Cu" "F.Mask" "F.Paste")
			(net 7 "+3V3")
			(pinfunction "VCC3P3")
			(pintype "power_in")
		)
		(pad "U23" smd circle
			(at 0.75 3.89 270)
			(size 0.5 0.5)
			(layers "F.Cu" "F.Mask" "F.Paste")
			(net 539 "unconnected-(U14E-RSVDU23_NC-PadU23)")
			(pinfunction "RSVDU23_NC")
			(pintype "passive+no_connect")
		)
		(pad "U25" smd circle
			(at 1.75 3.89 270)
			(size 0.5 0.5)
			(layers "F.Cu" "F.Mask" "F.Paste")
			(net 507 "unconnected-(U14E-RSVDU25_NC-PadU25)")
			(pinfunction "RSVDU25_NC")
			(pintype "passive+no_connect")
		)
		(pad "U27" smd circle
			(at 2.75 3.89 270)
			(size 0.5 0.5)
			(layers "F.Cu" "F.Mask" "F.Paste")
			(net 584 "unconnected-(U14E-RSVDU27_NC-PadU27)")
			(pinfunction "RSVDU27_NC")
			(pintype "passive+no_connect")
		)
		(pad "U29" smd circle
			(at 3.75 3.89 270)
			(size 0.5 0.5)
			(layers "F.Cu" "F.Mask" "F.Paste")
			(net 529 "unconnected-(U14E-RSVDU29_NC-PadU29)")
			(pinfunction "RSVDU29_NC")
			(pintype "passive+no_connect")
		)
		(pad "U31" smd circle
			(at 4.75 3.89 270)
			(size 0.5 0.5)
			(layers "F.Cu" "F.Mask" "F.Paste")
			(net 582 "unconnected-(U14G-RSVDU31_NC-PadU31)")
			(pinfunction "RSVDU31_NC")
			(pintype "passive+no_connect")
		)
		(pad "U33" smd circle
			(at 5.75 3.89 270)
			(size 0.5 0.5)
			(layers "F.Cu" "F.Mask" "F.Paste")
			(net 479 "unconnected-(U14G-RSVDU33_NC-PadU33)")
			(pinfunction "RSVDU33_NC")
			(pintype "passive+no_connect")
		)
		(pad "U35" smd circle
			(at 6.75 3.89 270)
			(size 0.5 0.5)
			(layers "F.Cu" "F.Mask" "F.Paste")
			(net 510 "unconnected-(U14G-RSVDU35_NC-PadU35)")
			(pinfunction "RSVDU35_NC")
			(pintype "passive+no_connect")
		)
		(pad "U37" smd circle
			(at 7.75 3.89 270)
			(size 0.5 0.5)
			(layers "F.Cu" "F.Mask" "F.Paste")
			(net 16 "/X710-AT2 PCIe/PCIe_JTAG.JTCK")
			(pinfunction "JTCK")
			(pintype "input")
		)
		(pad "U39" smd circle
			(at 8.75 3.89 270)
			(size 0.5 0.5)
			(layers "F.Cu" "F.Mask" "F.Paste")
			(net 35 "/X710-AT2 Misc/POR_BYPASS")
			(pinfunction "POR_BYPASS")
			(pintype "input")
		)
		(pad "U41" smd circle
			(at 9.75 3.89 270)
			(size 0.5 0.5)
			(layers "F.Cu" "F.Mask" "F.Paste")
			(net 73 "/X710-AT2 Misc/~{SMBALRT}")
			(pinfunction "~{SMBALRT}")
			(pintype "open_collector")
		)
		(pad "V2" smd circle
			(at -9.75 4.755 270)
			(size 0.5 0.5)
			(layers "F.Cu" "F.Mask" "F.Paste")
			(net 427 "Net-(U14H-SVR_IND)")
			(pinfunction "SVR_IND")
			(pintype "passive")
		)
		(pad "V4" smd circle
			(at -8.75 4.755 270)
			(size 0.5 0.5)
			(layers "F.Cu" "F.Mask" "F.Paste")
			(net 61 "/2xRJ45/~{P0_LED_ACT}")
			(pinfunction "LED0_0")
			(pintype "output")
		)
		(pad "V6" smd circle
			(at -7.75 4.755 270)
			(size 0.5 0.5)
			(layers "F.Cu" "F.Mask" "F.Paste")
			(net 60 "/2xRJ45/~{P0_LED_LINK_10G}")
			(pinfunction "LED0_1")
			(pintype "output")
		)
		(pad "V8" smd circle
			(at -6.75 4.755 270)
			(size 0.5 0.5)
			(layers "F.Cu" "F.Mask" "F.Paste")
			(net 572 "unconnected-(U14H-RSVDV8_NC-PadV8)")
			(pinfunction "RSVDV8_NC")
			(pintype "passive+no_connect")
		)
		(pad "V10" smd circle
			(at -5.75 4.755 270)
			(size 0.5 0.5)
			(layers "F.Cu" "F.Mask" "F.Paste")
			(net 465 "unconnected-(U14H-RSVDV10_NC-PadV10)")
			(pinfunction "RSVDV10_NC")
			(pintype "passive+no_connect")
		)
		(pad "V12" smd circle
			(at -4.75 4.755 270)
			(size 0.5 0.5)
			(layers "F.Cu" "F.Mask" "F.Paste")
			(net 23 "GND")
			(pinfunction "VSSA")
			(pintype "passive")
		)
		(pad "V14" smd circle
			(at -3.75 4.755 270)
			(size 0.5 0.5)
			(layers "F.Cu" "F.Mask" "F.Paste")
			(net 23 "GND")
			(pinfunction "VSSA")
			(pintype "passive")
		)
		(pad "V16" smd circle
			(at -2.75 4.755 270)
			(size 0.5 0.5)
			(layers "F.Cu" "F.Mask" "F.Paste")
			(net 23 "GND")
			(pinfunction "VSSA")
			(pintype "passive")
		)
		(pad "V18" smd circle
			(at -1.75 4.755 270)
			(size 0.5 0.5)
			(layers "F.Cu" "F.Mask" "F.Paste")
			(net 23 "GND")
			(pinfunction "VSSA")
			(pintype "passive")
		)
		(pad "V20" smd circle
			(at -0.75 4.755 270)
			(size 0.5 0.5)
			(layers "F.Cu" "F.Mask" "F.Paste")
			(net 23 "GND")
			(pinfunction "VSSA")
			(pintype "passive")
		)
		(pad "V22" smd circle
			(at 0.25 4.755 270)
			(size 0.5 0.5)
			(layers "F.Cu" "F.Mask" "F.Paste")
			(net 458 "unconnected-(U14E-RSVDV22_NC-PadV22)")
			(pinfunction "RSVDV22_NC")
			(pintype "passive+no_connect")
		)
		(pad "V24" smd circle
			(at 1.25 4.755 270)
			(size 0.5 0.5)
			(layers "F.Cu" "F.Mask" "F.Paste")
			(net 524 "unconnected-(U14E-RSVDV24_NC-PadV24)")
			(pinfunction "RSVDV24_NC")
			(pintype "passive+no_connect")
		)
		(pad "V26" smd circle
			(at 2.25 4.755 270)
			(size 0.5 0.5)
			(layers "F.Cu" "F.Mask" "F.Paste")
			(net 552 "unconnected-(U14E-RSVDV26_NC-PadV26)")
			(pinfunction "RSVDV26_NC")
			(pintype "passive+no_connect")
		)
		(pad "V28" smd circle
			(at 3.25 4.755 270)
			(size 0.5 0.5)
			(layers "F.Cu" "F.Mask" "F.Paste")
			(net 461 "unconnected-(U14E-RSVDV28_NC-PadV28)")
			(pinfunction "RSVDV28_NC")
			(pintype "passive+no_connect")
		)
		(pad "V30" smd circle
			(at 4.25 4.755 270)
			(size 0.5 0.5)
			(layers "F.Cu" "F.Mask" "F.Paste")
			(net 473 "unconnected-(U14G-RSVDV30_NC-PadV30)")
			(pinfunction "RSVDV30_NC")
			(pintype "passive+no_connect")
		)
		(pad "V32" smd circle
			(at 5.25 4.755 270)
			(size 0.5 0.5)
			(layers "F.Cu" "F.Mask" "F.Paste")
			(net 568 "unconnected-(U14G-RSVDV32_NC-PadV32)")
			(pinfunction "RSVDV32_NC")
			(pintype "passive+no_connect")
		)
		(pad "V34" smd circle
			(at 6.25 4.755 270)
			(size 0.5 0.5)
			(layers "F.Cu" "F.Mask" "F.Paste")
			(net 523 "unconnected-(U14G-RSVDV34_NC-PadV34)")
			(pinfunction "RSVDV34_NC")
			(pintype "passive+no_connect")
		)
		(pad "V36" smd circle
			(at 7.25 4.755 270)
			(size 0.5 0.5)
			(layers "F.Cu" "F.Mask" "F.Paste")
			(net 15 "/X710-AT2 PCIe/PCIe_JTAG.~{JRST}")
			(pinfunction "~{JRST}")
			(pintype "input")
		)
		(pad "V38" smd circle
			(at 8.25 4.755 270)
			(size 0.5 0.5)
			(layers "F.Cu" "F.Mask" "F.Paste")
			(net 4 "/X710-AT2 PCIe/PCIe_JTAG.JTMS")
			(pinfunction "JTMS")
			(pintype "input")
		)
		(pad "V40" smd circle
			(at 9.25 4.755 270)
			(size 0.5 0.5)
			(layers "F.Cu" "F.Mask" "F.Paste")
			(net 128 "/2xRJ45/~{P0_LINK_LESS_THAN_10G}")
			(pinfunction "GPIO_0")
			(pintype "tri_state")
		)
		(pad "V42" smd circle
			(at 10.25 4.755 270)
			(size 0.5 0.5)
			(layers "F.Cu" "F.Mask" "F.Paste")
			(net 578 "unconnected-(U14D-GPIO_3-PadV42)")
			(pinfunction "GPIO_3")
			(pintype "passive+no_connect")
		)
		(pad "W1" smd circle
			(at -10.25 5.62 270)
			(size 0.5 0.5)
			(layers "F.Cu" "F.Mask" "F.Paste")
			(net 96 "/X710-AT2 RSVD/RSVDW1_VSS")
			(pinfunction "RSVDW1_VSS")
			(pintype "passive")
		)
		(pad "W3" smd circle
			(at -9.25 5.62 270)
			(size 0.5 0.5)
			(layers "F.Cu" "F.Mask" "F.Paste")
			(net 23 "GND")
			(pinfunction "RSVDW3_VSS")
			(pintype "power_in")
		)
		(pad "W5" smd circle
			(at -8.25 5.62 270)
			(size 0.5 0.5)
			(layers "F.Cu" "F.Mask" "F.Paste")
			(net 94 "/X710-AT2 RSVD/RSVDW5_VSS")
			(pinfunction "RSVDW5_VSS")
			(pintype "passive")
		)
		(pad "W7" smd circle
			(at -7.25 5.62 270)
			(size 0.5 0.5)
			(layers "F.Cu" "F.Mask" "F.Paste")
			(net 90 "/X710-AT2 RSVD/DEBUG_W7")
			(pinfunction "DEBUG_W7")
			(pintype "passive")
		)
		(pad "W9" smd circle
			(at -6.25 5.62 270)
			(size 0.5 0.5)
			(layers "F.Cu" "F.Mask" "F.Paste")
			(net 9 "VCCD")
			(pinfunction "VCCD_A")
			(pintype "power_in")
		)
		(pad "W11" smd circle
			(at -5.25 5.62 270)
			(size 0.5 0.5)
			(layers "F.Cu" "F.Mask" "F.Paste")
			(net 7 "+3V3")
			(pinfunction "VCC3P3_A")
			(pintype "power_in")
		)
		(pad "W13" smd circle
			(at -4.25 5.62 270)
			(size 0.5 0.5)
			(layers "F.Cu" "F.Mask" "F.Paste")
			(net 1 "VCCA")
			(pinfunction "VCCA")
			(pintype "passive")
		)
		(pad "W15" smd circle
			(at -3.25 5.62 270)
			(size 0.5 0.5)
			(layers "F.Cu" "F.Mask" "F.Paste")
			(net 1 "VCCA")
			(pinfunction "VCCA")
			(pintype "passive")
		)
		(pad "W17" smd circle
			(at -2.25 5.62 270)
			(size 0.5 0.5)
			(layers "F.Cu" "F.Mask" "F.Paste")
			(net 1 "VCCA")
			(pinfunction "VCCA")
			(pintype "passive")
		)
		(pad "W19" smd circle
			(at -1.25 5.62 270)
			(size 0.5 0.5)
			(layers "F.Cu" "F.Mask" "F.Paste")
			(net 1 "VCCA")
			(pinfunction "VCCA")
			(pintype "passive")
		)
		(pad "W21" smd circle
			(at -0.25 5.62 270)
			(size 0.5 0.5)
			(layers "F.Cu" "F.Mask" "F.Paste")
			(net 1 "VCCA")
			(pinfunction "VCCA")
			(pintype "passive")
		)
		(pad "W23" smd circle
			(at 0.75 5.62 270)
			(size 0.5 0.5)
			(layers "F.Cu" "F.Mask" "F.Paste")
			(net 500 "unconnected-(U14E-RSVDW23_NC-PadW23)")
			(pinfunction "RSVDW23_NC")
			(pintype "passive+no_connect")
		)
		(pad "W25" smd circle
			(at 1.75 5.62 270)
			(size 0.5 0.5)
			(layers "F.Cu" "F.Mask" "F.Paste")
			(net 482 "unconnected-(U14E-RSVDW25_NC-PadW25)")
			(pinfunction "RSVDW25_NC")
			(pintype "passive+no_connect")
		)
		(pad "W27" smd circle
			(at 2.75 5.62 270)
			(size 0.5 0.5)
			(layers "F.Cu" "F.Mask" "F.Paste")
			(net 467 "unconnected-(U14E-RSVDW27_NC-PadW27)")
			(pinfunction "RSVDW27_NC")
			(pintype "passive+no_connect")
		)
		(pad "W29" smd circle
			(at 3.75 5.62 270)
			(size 0.5 0.5)
			(layers "F.Cu" "F.Mask" "F.Paste")
			(net 23 "GND")
			(pinfunction "VSSA")
			(pintype "passive")
		)
		(pad "W31" smd circle
			(at 4.75 5.62 270)
			(size 0.5 0.5)
			(layers "F.Cu" "F.Mask" "F.Paste")
			(net 23 "GND")
			(pinfunction "VSSA")
			(pintype "passive")
		)
		(pad "W33" smd circle
			(at 5.75 5.62 270)
			(size 0.5 0.5)
			(layers "F.Cu" "F.Mask" "F.Paste")
			(net 23 "GND")
			(pinfunction "VSSA")
			(pintype "passive")
		)
		(pad "W35" smd circle
			(at 6.75 5.62 270)
			(size 0.5 0.5)
			(layers "F.Cu" "F.Mask" "F.Paste")
			(net 23 "GND")
			(pinfunction "VSSA")
			(pintype "passive")
		)
	)
)
